# T6G (Grand Teton) — schematic netlist excerpt (pin names and nets, part order shuffled) for the footprints in the layout excerpt that follows; sources: Cadence DE-HDL packaged netlist, KiCad conversion of 04192023_DAF0TMB3IC0_F0TG_MB_C_brd_V02_OCP.brd

U86  SN74LVC1G07DBVR  IC  pkg SMLF  page 166
  NC  = NC
  A  = FM_SMERR_LED_N
  GND  = GND
  Y  = FM_SMERR_BUF_LED_N
  VCC  = P1V8_AUX

PC447  Q_CAP  0.22UF 16V 10% X7R  pkg 0402  page 222 : A = SW_PVDDIO_P1_BOOT1_R ; B = SW_PVDDIO_P1_BOOTR1

(kicad_pcb
	(version 20260206)
	(generator "pcbnew")
	(generator_version "10.0")
	(general
		(thickness 1.6)
		(legacy_teardrops no)
	)
	(paper "A4")
	(title_block
		(title "04192023_DAF0TMB3IC0_F0TG_MB_C_brd_V02_OCP.brd")
		(comment 1 "Grand Teton / footprints 2697-2698 of 8354")
	)
	(layers
		(0 "F.Cu" signal "TOP")
		(4 "In1.Cu" signal "GND")
		(6 "In2.Cu" signal "IN1")
		(8 "In3.Cu" signal "GND1")
		(10 "In4.Cu" signal "IN2")
		(12 "In5.Cu" signal "GND2")
		(14 "In6.Cu" signal "IN3")
		(16 "In7.Cu" signal "GND3")
		(18 "In8.Cu" signal "VCC")
		(20 "In9.Cu" signal "VCC1")
		(22 "In10.Cu" signal "GND4")
		(24 "In11.Cu" signal "IN4")
		(26 "In12.Cu" signal "GND5")
		(28 "In13.Cu" signal "IN5")
		(30 "In14.Cu" signal "GND6")
		(32 "In15.Cu" signal "IN6")
		(34 "In16.Cu" signal "GND7")
		(2 "B.Cu" signal "BOTTOM")
		(9 "F.Adhes" user "F.Adhesive")
		(11 "B.Adhes" user "B.Adhesive")
		(13 "F.Paste" user "Package Geometry/Pastemask Top")
		(15 "B.Paste" user "Package Geometry/Pastemask Bottom")
		(5 "F.SilkS" user "Ref Des/Silkscreen Top")
		(7 "B.SilkS" user "Ref Des/Silkscreen Bottom")
		(1 "F.Mask" user "Board Geometry/Soldermask Top")
		(3 "B.Mask" user "Board Geometry/Soldermask Bottom")
		(17 "Dwgs.User" user "User.Drawings")
		(19 "Cmts.User" user "User.Comments")
		(21 "Eco1.User" user "User.Eco1")
		(23 "Eco2.User" user "User.Eco2")
		(25 "Edge.Cuts" user "Board Geometry/Outline")
		(27 "Margin" user)
		(31 "F.CrtYd" user "Package Geometry/Place Bound Top")
		(29 "B.CrtYd" user "Package Geometry/Place Bound Bottom")
		(35 "F.Fab" user "Ref Des/Assembly Top")
		(33 "B.Fab" user "Ref Des/Assembly Bottom")
	)
	(footprint ""
		(layer "F.Cu")
		(at 346.549726 -28.291028 -90)
		(property "Reference" "U86"
			(at 1.804416 -2.63652 90)
			(unlocked yes)
			(layer "F.SilkS")
			(effects
				(font
					(size 0.7874 0.5842)
					(thickness 0.1524)
				)
				(justify left)
			)
		)
		(property "Value" ""
			(at 0 0 270)
			(layer "F.Fab")
			(effects
				(font
					(size 1.27 1.27)
				)
			)
		)
		(duplicate_pad_numbers_are_jumpers no)
		(fp_line
			(start -2.0574 1.651)
			(end -2.0574 -1.651)
			(stroke
				(width 0.1524)
				(type default)
			)
			(layer "F.SilkS")
		)
		(fp_line
			(start 2.0574 1.651)
			(end -2.0574 1.651)
			(stroke
				(width 0.1524)
				(type default)
			)
			(layer "F.SilkS")
		)
		(fp_line
			(start 0 -1.016)
			(end 0.381 -1.651)
			(stroke
				(width 0.1524)
				(type default)
			)
			(layer "F.SilkS")
		)
		(fp_line
			(start -2.0574 -1.651)
			(end -0.381 -1.651)
			(stroke
				(width 0.1524)
				(type default)
			)
			(layer "F.SilkS")
		)
		(fp_line
			(start -0.381 -1.651)
			(end 0 -1.016)
			(stroke
				(width 0.1524)
				(type default)
			)
			(layer "F.SilkS")
		)
		(fp_line
			(start 0.381 -1.651)
			(end 2.0574 -1.651)
			(stroke
				(width 0.1524)
				(type default)
			)
			(layer "F.SilkS")
		)
		(fp_line
			(start 2.0574 -1.651)
			(end 2.0574 1.651)
			(stroke
				(width 0.1524)
				(type default)
			)
			(layer "F.SilkS")
		)
		(fp_poly
			(pts
				(xy -2.159 -1.016) (xy -2.71272 -0.719328) (xy -2.71272 -1.344168)
			)
			(stroke
				(width 0)
				(type default)
			)
			(fill yes)
			(layer "F.SilkS")
		)
		(fp_line
			(start -0.899922 1.549908)
			(end -0.899922 1.199896)
			(stroke
				(width 0.1)
				(type default)
			)
			(layer "F.Fab")
		)
		(fp_line
			(start 0.899922 1.549908)
			(end -0.899922 1.549908)
			(stroke
				(width 0.1)
				(type default)
			)
			(layer "F.Fab")
		)
		(fp_line
			(start -1.599946 1.199896)
			(end -1.599946 -1.199896)
			(stroke
				(width 0.1)
				(type default)
			)
			(layer "F.Fab")
		)
		(fp_line
			(start -0.899922 1.199896)
			(end -1.599946 1.199896)
			(stroke
				(width 0.1)
				(type default)
			)
			(layer "F.Fab")
		)
		(fp_line
			(start 0.899922 1.199896)
			(end 0.899922 1.549908)
			(stroke
				(width 0.1)
				(type default)
			)
			(layer "F.Fab")
		)
		(fp_line
			(start 1.599946 1.199896)
			(end 0.899922 1.199896)
			(stroke
				(width 0.1)
				(type default)
			)
			(layer "F.Fab")
		)
		(fp_line
			(start -1.599946 -1.199896)
			(end -0.899922 -1.199896)
			(stroke
				(width 0.1)
				(type default)
			)
			(layer "F.Fab")
		)
		(fp_line
			(start -0.899922 -1.199896)
			(end -0.899922 -1.549908)
			(stroke
				(width 0.1)
				(type default)
			)
			(layer "F.Fab")
		)
		(fp_line
			(start 0.899922 -1.199896)
			(end 1.599946 -1.199896)
			(stroke
				(width 0.1)
				(type default)
			)
			(layer "F.Fab")
		)
		(fp_line
			(start 1.599946 -1.199896)
			(end 1.599946 1.199896)
			(stroke
				(width 0.1)
				(type default)
			)
			(layer "F.Fab")
		)
		(fp_line
			(start -0.899922 -1.549908)
			(end 0.899922 -1.549908)
			(stroke
				(width 0.1)
				(type default)
			)
			(layer "F.Fab")
		)
		(fp_line
			(start 0.899922 -1.549908)
			(end 0.899922 -1.199896)
			(stroke
				(width 0.1)
				(type default)
			)
			(layer "F.Fab")
		)
		(fp_poly
			(pts
				(xy -2.71272 -0.719328) (xy -2.71272 -1.344168) (xy -2.159 -1.016)
			)
			(stroke
				(width 0)
				(type default)
			)
			(fill yes)
			(layer "F.Fab")
		)
		(pad "1" smd rect
			(at -1.225042 -0.94996 180)
			(size 0.5588 1.3462)
			(layers "F.Cu" "F.Mask" "F.Paste")
			(net "Net_10731")
		)
		(pad "2" smd rect
			(at -1.225042 0 180)
			(size 0.5588 1.3462)
			(layers "F.Cu" "F.Mask" "F.Paste")
			(net "FM_SMERR_LED_N")
		)
		(pad "3" smd rect
			(at -1.225042 0.94996 180)
			(size 0.5588 1.3462)
			(layers "F.Cu" "F.Mask" "F.Paste")
			(net "GND")
		)
		(pad "4" smd rect
			(at 1.225042 0.94996 180)
			(size 0.5588 1.3462)
			(layers "F.Cu" "F.Mask" "F.Paste")
			(net "FM_SMERR_BUF_LED_N")
		)
		(pad "5" smd rect
			(at 1.225042 -0.94996 180)
			(size 0.5588 1.3462)
			(layers "F.Cu" "F.Mask" "F.Paste")
			(net "P1V8_AUX")
		)
	)
	(footprint ""
		(layer "F.Cu")
		(at 55.329328 -351.372932 -90)
		(property "Reference" "PC447"
			(at 0 0 270)
			(layer "F.SilkS")
			(hide yes)
			(effects
				(font
					(size 1.27 1.27)
				)
			)
		)
		(property "Value" ""
			(at 0 0 270)
			(layer "F.Fab")
			(effects
				(font
					(size 1.27 1.27)
				)
			)
		)
		(duplicate_pad_numbers_are_jumpers no)
		(fp_line
			(start -0.7874 0.4064)
			(end -0.7874 -0.4064)
			(stroke
				(width 0.1524)
				(type default)
			)
			(layer "F.SilkS")
		)
		(fp_line
			(start 0.7874 0.4064)
			(end -0.7874 0.4064)
			(stroke
				(width 0.1524)
				(type default)
			)
			(layer "F.SilkS")
		)
		(fp_line
			(start -0.7874 -0.4064)
			(end 0.7874 -0.4064)
			(stroke
				(width 0.1524)
				(type default)
			)
			(layer "F.SilkS")
		)
		(fp_line
			(start 0.7874 -0.4064)
			(end 0.7874 0.4064)
			(stroke
				(width 0.1524)
				(type default)
			)
			(layer "F.SilkS")
		)
		(fp_line
			(start -0.67945 0.3048)
			(end -0.67945 -0.305054)
			(stroke
				(width 0.1)
				(type default)
			)
			(layer "F.Fab")
		)
		(fp_line
			(start -0.12065 0.3048)
			(end -0.67945 0.3048)
			(stroke
				(width 0.1)
				(type default)
			)
			(layer "F.Fab")
		)
		(fp_line
			(start 0.120396 0.3048)
			(end 0.120396 0.2794)
			(stroke
				(width 0.1)
				(type default)
			)
			(layer "F.Fab")
		)
		(fp_line
			(start 0.67945 0.3048)
			(end 0.120396 0.3048)
			(stroke
				(width 0.1)
				(type default)
			)
			(layer "F.Fab")
		)
		(fp_line
			(start -0.12065 0.2794)
			(end -0.12065 0.3048)
			(stroke
				(width 0.1)
				(type default)
			)
			(layer "F.Fab")
		)
		(fp_line
			(start 0.120396 0.2794)
			(end -0.12065 0.2794)
			(stroke
				(width 0.1)
				(type default)
			)
			(layer "F.Fab")
		)
		(fp_line
			(start -0.12065 -0.2794)
			(end 0.12065 -0.2794)
			(stroke
				(width 0.1)
				(type default)
			)
			(layer "F.Fab")
		)
		(fp_line
			(start 0.12065 -0.2794)
			(end 0.12065 -0.3048)
			(stroke
				(width 0.1)
				(type default)
			)
			(layer "F.Fab")
		)
		(fp_line
			(start 0.12065 -0.3048)
			(end 0.67945 -0.3048)
			(stroke
				(width 0.1)
				(type default)
			)
			(layer "F.Fab")
		)
		(fp_line
			(start 0.67945 -0.3048)
			(end 0.67945 0.3048)
			(stroke
				(width 0.1)
				(type default)
			)
			(layer "F.Fab")
		)
		(fp_line
			(start -0.67945 -0.305054)
			(end -0.12065 -0.305054)
			(stroke
				(width 0.1)
				(type default)
			)
			(layer "F.Fab")
		)
		(fp_line
			(start -0.12065 -0.305054)
			(end -0.12065 -0.2794)
			(stroke
				(width 0.1)
				(type default)
			)
			(layer "F.Fab")
		)
		(pad "1" smd circle
			(at -0.40005 0 270)
			(size 0 0)
			(layers "F.Cu" "F.Mask" "F.Paste")
			(net "SW_PVDDIO_P1_BOOT1_R")
		)
		(pad "2" smd circle
			(at 0.40005 0 270)
			(size 0 0)
			(layers "F.Cu" "F.Mask" "F.Paste")
			(net "SW_PVDDIO_P1_BOOTR1")
		)
	)
)
